(kicad_pcb
	(version 20241229)
	(generator "pcbnew")
	(generator_version "9.0")
	(general
		(thickness 1.6)
		(legacy_teardrops no)
	)
	(paper "A4")
	(title_block
		(title "OCuLink to PCIe adapter")
		(date "2025-06-18")
		(rev "1.0.0")
		(company "Antmicro Ltd")
		(comment 1 "www.antmicro.com")
		(comment 9 "footprints 52-56 of 159")
	)
	(layers
		(0 "F.Cu" signal)
		(4 "In1.Cu" signal)
		(6 "In2.Cu" signal)
		(2 "B.Cu" signal)
		(9 "F.Adhes" user "F.Adhesive")
		(11 "B.Adhes" user "B.Adhesive")
		(13 "F.Paste" user)
		(15 "B.Paste" user)
		(5 "F.SilkS" user "F.Silkscreen")
		(7 "B.SilkS" user "B.Silkscreen")
		(1 "F.Mask" user)
		(3 "B.Mask" user)
		(17 "Dwgs.User" user "User.Drawings")
		(19 "Cmts.User" user "User.Comments")
		(21 "Eco1.User" user "User.Eco1")
		(23 "Eco2.User" user "User.Eco2")
		(25 "Edge.Cuts" user)
		(27 "Margin" user)
		(31 "F.CrtYd" user "F.Courtyard")
		(29 "B.CrtYd" user "B.Courtyard")
		(35 "F.Fab" user)
		(33 "B.Fab" user)
	)
	(footprint "antmicro-footprints:C_0805_2012Metric"
		(layer "F.Cu")
		(at 130.9 131.05 -90)
		(descr "Capacitor SMD 0805")
		(tags "capacitor SMD 0805")
		(property "Reference" "C2"
			(at -4.45 0.4 90)
			(layer "F.SilkS")
			(effects
				(font
					(size 0.7 0.7)
					(thickness 0.15)
				)
				(justify right top)
			)
		)
		(property "Value" "C_22u_25V_0805"
			(at -2.055717 1.963153 90)
			(layer "F.Fab")
			(effects
				(font
					(size 0.7 0.7)
					(thickness 0.15)
				)
				(justify right top)
			)
		)
		(property "Datasheet" "https://product.samsungsem.com/mlcc/CL21A226MAYNNN.do"
			(at 0 0 90)
			(layer "F.Fab")
			(hide yes)
			(effects
				(font
					(size 1.27 1.27)
					(thickness 0.15)
				)
			)
		)
		(property "Description" "SMT Multilayer Ceramic Capacitor, 22uF, +/-20%, 25V, X5R, 0805 [2012 Metric]"
			(at 0 0 90)
			(layer "F.Fab")
			(hide yes)
			(effects
				(font
					(size 1.27 1.27)
					(thickness 0.15)
				)
			)
		)
		(property "MPN" "CL21A226MAYNNNE"
			(at 0 0 270)
			(unlocked yes)
			(layer "F.Fab")
			(hide yes)
			(effects
				(font
					(size 1 1)
					(thickness 0.15)
				)
			)
		)
		(property "Manufacturer" "Samsung Electro-Mechanics"
			(at 0 0 270)
			(unlocked yes)
			(layer "F.Fab")
			(hide yes)
			(effects
				(font
					(size 1 1)
					(thickness 0.15)
				)
			)
		)
		(property "License" "Apache-2.0"
			(at 0 0 270)
			(unlocked yes)
			(layer "F.Fab")
			(hide yes)
			(effects
				(font
					(size 1 1)
					(thickness 0.15)
				)
			)
		)
		(property "Author" "Antmicro"
			(at 0 0 270)
			(unlocked yes)
			(layer "F.Fab")
			(hide yes)
			(effects
				(font
					(size 1 1)
					(thickness 0.15)
				)
			)
		)
		(property "Val" "22u"
			(at 0 0 270)
			(unlocked yes)
			(layer "F.Fab")
			(hide yes)
			(effects
				(font
					(size 1 1)
					(thickness 0.15)
				)
			)
		)
		(property "Voltage" "25V"
			(at 0 0 270)
			(unlocked yes)
			(layer "F.Fab")
			(hide yes)
			(effects
				(font
					(size 1 1)
					(thickness 0.15)
				)
			)
		)
		(property "Dielectric" "X5R"
			(at 0 0 270)
			(unlocked yes)
			(layer "F.Fab")
			(hide yes)
			(effects
				(font
					(size 1 1)
					(thickness 0.15)
				)
			)
		)
		(property "Public" "False"
			(at 0 0 270)
			(unlocked yes)
			(layer "F.Fab")
			(hide yes)
			(effects
				(font
					(size 1 1)
					(thickness 0.15)
				)
			)
		)
		(sheetname "/Power/")
		(sheetfile "power.kicad_sch")
		(attr smd)
		(fp_line
			(start -0.3 0.7)
			(end 0.3 0.7)
			(stroke
				(width 0.15)
				(type solid)
			)
			(layer "F.SilkS")
		)
		(fp_line
			(start -0.3 -0.7)
			(end 0.3 -0.7)
			(stroke
				(width 0.15)
				(type solid)
			)
			(layer "F.SilkS")
		)
		(fp_rect
			(start 1.95 -0.9)
			(end -1.95 0.9)
			(stroke
				(width 0.05)
				(type default)
			)
			(fill no)
			(layer "F.CrtYd")
		)
		(fp_rect
			(start -0.95 -0.675)
			(end 0.95 0.675)
			(stroke
				(width 0.15)
				(type solid)
			)
			(fill no)
			(layer "F.Fab")
		)
		(fp_text user "Author: Antmicro"
			(at -1.9 5.947 90)
			(layer "F.Fab")
			(effects
				(font
					(size 0.7 0.7)
					(thickness 0.15)
				)
				(justify right top)
			)
		)
		(fp_text user "${REFERENCE}"
			(at -1.899999 3.947 90)
			(layer "F.Fab")
			(effects
				(font
					(size 0.7 0.7)
					(thickness 0.15)
				)
				(justify right top)
			)
		)
		(fp_text user "License: Apache-2.0"
			(at -1.9 4.947 90)
			(layer "F.Fab")
			(effects
				(font
					(size 0.7 0.7)
					(thickness 0.15)
				)
				(justify right top)
			)
		)
		(pad "1" smd roundrect
			(at -1.1 0 270)
			(size 1.2 1.3)
			(layers "F.Cu" "F.Mask" "F.Paste")
			(roundrect_rratio 0.25)
			(net 66 "GND")
			(pintype "passive")
		)
		(pad "2" smd roundrect
			(at 1.1 0 270)
			(size 1.2 1.3)
			(layers "F.Cu" "F.Mask" "F.Paste")
			(roundrect_rratio 0.25)
			(net 87 "+12V")
			(pintype "passive")
		)
	)
	(footprint "antmicro-footprints:R_0402_1005Metric"
		(layer "F.Cu")
		(at 121.2245 150.154999 180)
		(descr "Resistor SMD 0402")
		(tags "resistor SMD 0402")
		(property "Reference" "R15"
			(at 3.2245 -0.445001 180)
			(layer "F.SilkS")
			(effects
				(font
					(size 0.7 0.7)
					(thickness 0.15)
				)
				(justify left bottom)
			)
		)
		(property "Value" "R_100k_0402"
			(at -1.011843 1.772046 0)
			(layer "F.Fab")
			(effects
				(font
					(size 0.7 0.7)
					(thickness 0.15)
				)
				(justify right top)
			)
		)
		(property "Datasheet" "https://www.bourns.com/docs/product-datasheets/cr.pdf"
			(at 0 0 0)
			(layer "F.Fab")
			(hide yes)
			(effects
				(font
					(size 1.27 1.27)
					(thickness 0.15)
				)
			)
		)
		(property "Description" "SMD Chip Resistor, 100 kohm, ± 1%, 62.5 mW, 0402 [1005 Metric], Thick Film, General Purpose"
			(at 0 0 0)
			(layer "F.Fab")
			(hide yes)
			(effects
				(font
					(size 1.27 1.27)
					(thickness 0.15)
				)
			)
		)
		(property "MPN" "CR0402-FX-1003GLF"
			(at 0 0 180)
			(unlocked yes)
			(layer "F.Fab")
			(hide yes)
			(effects
				(font
					(size 1 1)
					(thickness 0.15)
				)
			)
		)
		(property "Manufacturer" "Bourns"
			(at 0 0 180)
			(unlocked yes)
			(layer "F.Fab")
			(hide yes)
			(effects
				(font
					(size 1 1)
					(thickness 0.15)
				)
			)
		)
		(property "License" "Apache-2.0"
			(at 0 0 180)
			(unlocked yes)
			(layer "F.Fab")
			(hide yes)
			(effects
				(font
					(size 1 1)
					(thickness 0.15)
				)
			)
		)
		(property "Author" "Antmicro"
			(at 0 0 180)
			(unlocked yes)
			(layer "F.Fab")
			(hide yes)
			(effects
				(font
					(size 1 1)
					(thickness 0.15)
				)
			)
		)
		(property "Val" "100k"
			(at 0 0 180)
			(unlocked yes)
			(layer "F.Fab")
			(hide yes)
			(effects
				(font
					(size 1 1)
					(thickness 0.15)
				)
			)
		)
		(property "Tolerance" "1%"
			(at 0 0 180)
			(unlocked yes)
			(layer "F.Fab")
			(hide yes)
			(effects
				(font
					(size 1 1)
					(thickness 0.15)
				)
			)
		)
		(sheetname "/Power/")
		(sheetfile "power.kicad_sch")
		(attr smd)
		(fp_rect
			(start -0.925 -0.47)
			(end 0.925 0.47)
			(stroke
				(width 0.05)
				(type default)
			)
			(fill no)
			(layer "F.CrtYd")
		)
		(fp_rect
			(start -0.5 -0.25)
			(end 0.5 0.25)
			(stroke
				(width 0.15)
				(type solid)
			)
			(fill no)
			(layer "F.Fab")
		)
		(fp_text user "License: Apache-2.0"
			(at -0.949999 5.169 0)
			(layer "F.Fab")
			(effects
				(font
					(size 0.7 0.7)
					(thickness 0.15)
				)
				(justify right top)
			)
		)
		(fp_text user "${REFERENCE}"
			(at 0 0 180)
			(layer "F.Fab")
			(effects
				(font
					(size 0.7 0.7)
					(thickness 0.15)
				)
				(justify left bottom)
			)
		)
		(fp_text user "Author: Antmicro"
			(at -0.95 4.169 0)
			(layer "F.Fab")
			(effects
				(font
					(size 0.7 0.7)
					(thickness 0.15)
				)
				(justify right top)
			)
		)
		(pad "1" smd roundrect
			(at -0.48 0 180)
			(size 0.59 0.64)
			(layers "F.Cu" "F.Mask" "F.Paste")
			(roundrect_rratio 0.25)
			(net 66 "GND")
			(pintype "passive")
		)
		(pad "2" smd roundrect
			(at 0.48 0 180)
			(size 0.59 0.64)
			(layers "F.Cu" "F.Mask" "F.Paste")
			(roundrect_rratio 0.25)
			(net 105 "/Power/3V3_PG")
			(pintype "passive")
		)
	)
	(footprint "antmicro-footprints:R_0402_1005Metric"
		(layer "F.Cu")
		(at 131.72 152.999999)
		(descr "Resistor SMD 0402")
		(tags "resistor SMD 0402")
		(property "Reference" "R14"
			(at 1.08 0.500001 180)
			(layer "F.SilkS")
			(effects
				(font
					(size 0.7 0.7)
					(thickness 0.15)
				)
				(justify left bottom)
			)
		)
		(property "Value" "R_1k_0402"
			(at -1.011843 1.772046 0)
			(layer "F.Fab")
			(effects
				(font
					(size 0.7 0.7)
					(thickness 0.15)
				)
				(justify left bottom)
			)
		)
		(property "Datasheet" "https://www.bourns.com/docs/product-datasheets/cr.pdf"
			(at 0 0 0)
			(layer "F.Fab")
			(hide yes)
			(effects
				(font
					(size 1.27 1.27)
					(thickness 0.15)
				)
			)
		)
		(property "Description" "SMD Chip Resistor, 1 kohm, ± 1%, 63 mW, 0402 [1005 Metric], Thick Film, General Purpose"
			(at 0 0 0)
			(layer "F.Fab")
			(hide yes)
			(effects
				(font
					(size 1.27 1.27)
					(thickness 0.15)
				)
			)
		)
		(property "MPN" "CR0402-FX-1001GLF"
			(at 0 0 0)
			(unlocked yes)
			(layer "F.Fab")
			(hide yes)
			(effects
				(font
					(size 1 1)
					(thickness 0.15)
				)
			)
		)
		(property "Manufacturer" "Bourns"
			(at 0 0 0)
			(unlocked yes)
			(layer "F.Fab")
			(hide yes)
			(effects
				(font
					(size 1 1)
					(thickness 0.15)
				)
			)
		)
		(property "License" "Apache-2.0"
			(at 0 0 0)
			(unlocked yes)
			(layer "F.Fab")
			(hide yes)
			(effects
				(font
					(size 1 1)
					(thickness 0.15)
				)
			)
		)
		(property "Author" "Antmicro"
			(at 0 0 0)
			(unlocked yes)
			(layer "F.Fab")
			(hide yes)
			(effects
				(font
					(size 1 1)
					(thickness 0.15)
				)
			)
		)
		(property "Val" "1k"
			(at 0 0 0)
			(unlocked yes)
			(layer "F.Fab")
			(hide yes)
			(effects
				(font
					(size 1 1)
					(thickness 0.15)
				)
			)
		)
		(property "Tolerance" "1%"
			(at 0 0 0)
			(unlocked yes)
			(layer "F.Fab")
			(hide yes)
			(effects
				(font
					(size 1 1)
					(thickness 0.15)
				)
			)
		)
		(sheetname "/Power/")
		(sheetfile "power.kicad_sch")
		(attr smd)
		(fp_rect
			(start -0.925 -0.47)
			(end 0.925 0.47)
			(stroke
				(width 0.05)
				(type default)
			)
			(fill no)
			(layer "F.CrtYd")
		)
		(fp_rect
			(start -0.5 -0.25)
			(end 0.5 0.25)
			(stroke
				(width 0.15)
				(type solid)
			)
			(fill no)
			(layer "F.Fab")
		)
		(fp_text user "License: Apache-2.0"
			(at -0.949999 5.169 0)
			(layer "F.Fab")
			(effects
				(font
					(size 0.7 0.7)
					(thickness 0.15)
				)
				(justify left bottom)
			)
		)
		(fp_text user "${REFERENCE}"
			(at 0 0 0)
			(layer "F.Fab")
			(effects
				(font
					(size 0.7 0.7)
					(thickness 0.15)
				)
				(justify left bottom)
			)
		)
		(fp_text user "Author: Antmicro"
			(at -0.95 4.169 0)
			(layer "F.Fab")
			(effects
				(font
					(size 0.7 0.7)
					(thickness 0.15)
				)
				(justify left bottom)
			)
		)
		(pad "1" smd roundrect
			(at -0.48 0)
			(size 0.59 0.64)
			(layers "F.Cu" "F.Mask" "F.Paste")
			(roundrect_rratio 0.25)
			(net 66 "GND")
			(pintype "passive")
		)
		(pad "2" smd roundrect
			(at 0.48 0)
			(size 0.59 0.64)
			(layers "F.Cu" "F.Mask" "F.Paste")
			(roundrect_rratio 0.25)
			(net 91 "Net-(D3-C)")
			(pintype "passive")
		)
	)
	(footprint "antmicro-footprints:C_Pol_Vishay-T59-EE"
		(layer "F.Cu")
		(at 127.9 116 180)
		(property "Reference" "C30"
			(at -4.9 -0.4 180)
			(layer "F.SilkS")
			(effects
				(font
					(size 0.7 0.7)
					(thickness 0.15)
				)
				(justify left bottom)
			)
		)
		(property "Value" "C_Pol_150u_30V_Vishay-T59-EE"
			(at -5.08 5.08 180)
			(unlocked yes)
			(layer "F.Fab")
			(effects
				(font
					(size 0.7 0.7)
					(thickness 0.15)
				)
				(justify left bottom)
			)
		)
		(property "Datasheet" "https://www.vishay.com/docs/40191/t59.pdf"
			(at 0 0 0)
			(layer "F.Fab")
			(hide yes)
			(effects
				(font
					(size 1.27 1.27)
					(thickness 0.15)
				)
			)
		)
		(property "Description" "Tantalum Capacitors - Polymer 150uF 30volts 20% 75mohms maxESR"
			(at 0 0 0)
			(layer "F.Fab")
			(hide yes)
			(effects
				(font
					(size 1.27 1.27)
					(thickness 0.15)
				)
			)
		)
		(property "MPN" "T59EE157M030C0075"
			(at 0 0 180)
			(unlocked yes)
			(layer "F.Fab")
			(hide yes)
			(effects
				(font
					(size 1 1)
					(thickness 0.15)
				)
			)
		)
		(property "Manufacturer" "Vishay"
			(at 0 0 180)
			(unlocked yes)
			(layer "F.Fab")
			(hide yes)
			(effects
				(font
					(size 1 1)
					(thickness 0.15)
				)
			)
		)
		(property "Voltage" "30V"
			(at 0 0 180)
			(unlocked yes)
			(layer "F.Fab")
			(hide yes)
			(effects
				(font
					(size 1 1)
					(thickness 0.15)
				)
			)
		)
		(property "Val" "150u"
			(at 0 0 180)
			(unlocked yes)
			(layer "F.Fab")
			(hide yes)
			(effects
				(font
					(size 1 1)
					(thickness 0.15)
				)
			)
		)
		(property "Author" "Antmicro"
			(at 0 0 180)
			(unlocked yes)
			(layer "F.Fab")
			(hide yes)
			(effects
				(font
					(size 1 1)
					(thickness 0.15)
				)
			)
		)
		(property "License" "Apache-2.0"
			(at 0 0 180)
			(unlocked yes)
			(layer "F.Fab")
			(hide yes)
			(effects
				(font
					(size 1 1)
					(thickness 0.15)
				)
			)
		)
		(property "Dielectric" "template_dielectric"
			(at 0 0 180)
			(unlocked yes)
			(layer "F.Fab")
			(hide yes)
			(effects
				(font
					(size 1 1)
					(thickness 0.15)
				)
			)
		)
		(sheetname "/Power/")
		(sheetfile "power.kicad_sch")
		(attr smd)
		(fp_line
			(start -2 2.25)
			(end 2 2.25)
			(stroke
				(width 0.15)
				(type solid)
			)
			(layer "F.SilkS")
		)
		(fp_line
			(start -2 -2.25)
			(end 2 -2.25)
			(stroke
				(width 0.15)
				(type solid)
			)
			(layer "F.SilkS")
		)
		(fp_line
			(start -3.5 -2.8)
			(end -3.5 -3.2)
			(stroke
				(width 0.15)
				(type solid)
			)
			(layer "F.SilkS")
		)
		(fp_line
			(start -3.7 -3)
			(end -3.3 -3)
			(stroke
				(width 0.15)
				(type solid)
			)
			(layer "F.SilkS")
		)
		(fp_rect
			(start -4.9 -2.9)
			(end 4.9 2.9)
			(stroke
				(width 0.05)
				(type solid)
			)
			(fill no)
			(layer "F.CrtYd")
		)
		(fp_rect
			(start -3.75 -2.25)
			(end 3.75 2.25)
			(stroke
				(width 0.15)
				(type solid)
			)
			(fill no)
			(layer "F.Fab")
		)
		(fp_text user "Author: Antmicro"
			(at -5.079999 7.08 0)
			(layer "F.Fab")
			(effects
				(font
					(size 0.7 0.7)
					(thickness 0.15)
				)
				(justify right top)
			)
		)
		(fp_text user "License: Apache-2.0"
			(at -5.08 9.48 0)
			(layer "F.Fab")
			(effects
				(font
					(size 0.7 0.7)
					(thickness 0.15)
				)
				(justify right top)
			)
		)
		(fp_text user "${REFERENCE}"
			(at 0 -0.175 180)
			(layer "F.Fab")
			(effects
				(font
					(size 0.7 0.7)
					(thickness 0.15)
				)
				(justify left bottom)
			)
		)
		(pad "1" smd trapezoid
			(at -3.4 0 180)
			(size 2.5 5.3)
			(layers "F.Cu" "F.Mask" "F.Paste")
			(net 87 "+12V")
			(pintype "passive")
		)
		(pad "2" smd trapezoid
			(at 3.4 0 180)
			(size 2.5 5.3)
			(layers "F.Cu" "F.Mask" "F.Paste")
			(net 66 "GND")
			(pintype "passive")
		)
	)
	(footprint "antmicro-footprints:C_0805_2012Metric"
		(layer "F.Cu")
		(at 134.5 93.5 -90)
		(descr "Capacitor SMD 0805")
		(tags "capacitor SMD 0805")
		(property "Reference" "C18"
			(at -2.5 3.9 90)
			(layer "F.SilkS")
			(effects
				(font
					(size 0.7 0.7)
					(thickness 0.15)
				)
				(justify right top)
			)
		)
		(property "Value" "C_22u_25V_0805"
			(at -2.055717 1.963153 90)
			(layer "F.Fab")
			(effects
				(font
					(size 0.7 0.7)
					(thickness 0.15)
				)
				(justify right top)
			)
		)
		(property "Datasheet" "https://product.samsungsem.com/mlcc/CL21A226MAYNNN.do"
			(at 0 0 90)
			(layer "F.Fab")
			(hide yes)
			(effects
				(font
					(size 1.27 1.27)
					(thickness 0.15)
				)
			)
		)
		(property "Description" "SMT Multilayer Ceramic Capacitor, 22uF, +/-20%, 25V, X5R, 0805 [2012 Metric]"
			(at 0 0 90)
			(layer "F.Fab")
			(hide yes)
			(effects
				(font
					(size 1.27 1.27)
					(thickness 0.15)
				)
			)
		)
		(property "MPN" "CL21A226MAYNNNE"
			(at 0 0 270)
			(unlocked yes)
			(layer "F.Fab")
			(hide yes)
			(effects
				(font
					(size 1 1)
					(thickness 0.15)
				)
			)
		)
		(property "Manufacturer" "Samsung Electro-Mechanics"
			(at 0 0 270)
			(unlocked yes)
			(layer "F.Fab")
			(hide yes)
			(effects
				(font
					(size 1 1)
					(thickness 0.15)
				)
			)
		)
		(property "License" "Apache-2.0"
			(at 0 0 270)
			(unlocked yes)
			(layer "F.Fab")
			(hide yes)
			(effects
				(font
					(size 1 1)
					(thickness 0.15)
				)
			)
		)
		(property "Author" "Antmicro"
			(at 0 0 270)
			(unlocked yes)
			(layer "F.Fab")
			(hide yes)
			(effects
				(font
					(size 1 1)
					(thickness 0.15)
				)
			)
		)
		(property "Val" "22u"
			(at 0 0 270)
			(unlocked yes)
			(layer "F.Fab")
			(hide yes)
			(effects
				(font
					(size 1 1)
					(thickness 0.15)
				)
			)
		)
		(property "Voltage" "25V"
			(at 0 0 270)
			(unlocked yes)
			(layer "F.Fab")
			(hide yes)
			(effects
				(font
					(size 1 1)
					(thickness 0.15)
				)
			)
		)
		(property "Dielectric" "X5R"
			(at 0 0 270)
			(unlocked yes)
			(layer "F.Fab")
			(hide yes)
			(effects
				(font
					(size 1 1)
					(thickness 0.15)
				)
			)
		)
		(property "Public" "False"
			(at 0 0 270)
			(unlocked yes)
			(layer "F.Fab")
			(hide yes)
			(effects
				(font
					(size 1 1)
					(thickness 0.15)
				)
			)
		)
		(sheetname "/USB-PD/")
		(sheetfile "usb-pd.kicad_sch")
		(attr smd)
		(fp_line
			(start -0.3 0.7)
			(end 0.3 0.7)
			(stroke
				(width 0.15)
				(type solid)
			)
			(layer "F.SilkS")
		)
		(fp_line
			(start -0.3 -0.7)
			(end 0.3 -0.7)
			(stroke
				(width 0.15)
				(type solid)
			)
			(layer "F.SilkS")
		)
		(fp_rect
			(start 1.95 -0.9)
			(end -1.95 0.9)
			(stroke
				(width 0.05)
				(type default)
			)
			(fill no)
			(layer "F.CrtYd")
		)
		(fp_rect
			(start -0.95 -0.675)
			(end 0.95 0.675)
			(stroke
				(width 0.15)
				(type solid)
			)
			(fill no)
			(layer "F.Fab")
		)
		(fp_text user "${REFERENCE}"
			(at 0 0 90)
			(layer "F.Fab")
			(effects
				(font
					(size 0.7 0.7)
					(thickness 0.15)
				)
				(justify right top)
			)
		)
		(fp_text user "Author: Antmicro"
			(at -1.9 5.947 90)
			(layer "F.Fab")
			(effects
				(font
					(size 0.7 0.7)
					(thickness 0.15)
				)
				(justify right top)
			)
		)
		(fp_text user "License: Apache-2.0"
			(at -1.9 4.947 90)
			(layer "F.Fab")
			(effects
				(font
					(size 0.7 0.7)
					(thickness 0.15)
				)
				(justify right top)
			)
		)
		(pad "1" smd roundrect
			(at -1.1 0 270)
			(size 1.2 1.3)
			(layers "F.Cu" "F.Mask" "F.Paste")
			(roundrect_rratio 0.25)
			(net 66 "GND")
			(pintype "passive")
		)
		(pad "2" smd roundrect
			(at 1.1 0 270)
			(size 1.2 1.3)
			(layers "F.Cu" "F.Mask" "F.Paste")
			(roundrect_rratio 0.25)
			(net 187 "/USB-PD/12V_CONV")
			(pintype "passive")
		)
	)
)
